FILE_TYPE=LIBRARY_PARTS;
primitive 'CONN9_GSB3111315HR';
  pin
    'VBUS':
      PIN_NUMBER='(1)';
      PINUSE='POWER';
      NO_LOAD_CHECK='Both';
      NO_IO_CHECK='Both';
      NO_ASSERT_CHECK='TRUE';
      NO_DIR_CHECK='TRUE';
      ALLOW_CONNECT='TRUE';
    'GND':
      PIN_NUMBER='(4)';
      PINUSE='POWER';
      NO_LOAD_CHECK='Both';
      NO_IO_CHECK='Both';
      NO_ASSERT_CHECK='TRUE';
      NO_DIR_CHECK='TRUE';
      ALLOW_CONNECT='TRUE';
    'G1':
      PIN_NUMBER='(G1)';
      PINUSE='POWER';
      NO_LOAD_CHECK='Both';
      NO_IO_CHECK='Both';
      NO_ASSERT_CHECK='TRUE';
      NO_DIR_CHECK='TRUE';
      ALLOW_CONNECT='TRUE';
    'G2':
      PIN_NUMBER='(G2)';
      PINUSE='POWER';
      NO_LOAD_CHECK='Both';
      NO_IO_CHECK='Both';
      NO_ASSERT_CHECK='TRUE';
      NO_DIR_CHECK='TRUE';
      ALLOW_CONNECT='TRUE';
    'SSTX+':
      PIN_NUMBER='(9)';
      INPUT_LOAD='(-0.01,0.01)';
    'SSTX-':
      PIN_NUMBER='(8)';
      INPUT_LOAD='(-0.01,0.01)';
    'D-':
      PIN_NUMBER='(2)';
      BIDIRECTIONAL='TRUE';
      INPUT_LOAD='(-0.01,0.01)';
      OUTPUT_LOAD='(1.0,-1.0)';
    'D+':
      PIN_NUMBER='(3)';
      BIDIRECTIONAL='TRUE';
      INPUT_LOAD='(-0.01,0.01)';
      OUTPUT_LOAD='(1.0,-1.0)';
    'SSRX+':
      PIN_NUMBER='(6)';
      OUTPUT_LOAD='(1.0,-1.0)';
    'GND_D':
      PIN_NUMBER='(7)';
      PINUSE='POWER';
      NO_LOAD_CHECK='Both';
      NO_IO_CHECK='Both';
      NO_ASSERT_CHECK='TRUE';
      NO_DIR_CHECK='TRUE';
      ALLOW_CONNECT='TRUE';
    'SSRX-':
      PIN_NUMBER='(5)';
      OUTPUT_LOAD='(1.0,-1.0)';
  end_pin;
  body
    PART_NAME='CONN9_GSB3111315HR';
    BODY_NAME='CONN9_GSB3111315HR';
    PHYS_DES_PREFIX='J';
    CLASS='IO';
  end_body;
end_primitive;

END.
